# T6G (Grand Teton) — schematic netlist excerpt (pin names and nets, part order shuffled) for the footprints in the layout excerpt that follows; sources: Cadence DE-HDL packaged netlist, KiCad conversion of 04192023_DAF0TMB3IC0_F0TG_MB_C_brd_V02_OCP.brd

R6082  Q_RES  4.7K 5% CHIP  pkg 0402LF  page 28 : A = PVDD11_S3_P0 ; B = SMB_CPU0_2_SDA
C1085  Q_CAP  100PF 50V 5% EMPTY  pkg 0402  page 258 : A = P5V_AUX_ADC_MAM ; B = GND

(kicad_pcb
	(version 20260206)
	(generator "pcbnew")
	(generator_version "10.0")
	(general
		(thickness 1.6)
		(legacy_teardrops no)
	)
	(paper "A4")
	(title_block
		(title "04192023_DAF0TMB3IC0_F0TG_MB_C_brd_V02_OCP.brd")
		(comment 1 "Grand Teton / footprints 5854-5855 of 8354")
	)
	(layers
		(0 "F.Cu" signal "TOP")
		(4 "In1.Cu" signal "GND")
		(6 "In2.Cu" signal "IN1")
		(8 "In3.Cu" signal "GND1")
		(10 "In4.Cu" signal "IN2")
		(12 "In5.Cu" signal "GND2")
		(14 "In6.Cu" signal "IN3")
		(16 "In7.Cu" signal "GND3")
		(18 "In8.Cu" signal "VCC")
		(20 "In9.Cu" signal "VCC1")
		(22 "In10.Cu" signal "GND4")
		(24 "In11.Cu" signal "IN4")
		(26 "In12.Cu" signal "GND5")
		(28 "In13.Cu" signal "IN5")
		(30 "In14.Cu" signal "GND6")
		(32 "In15.Cu" signal "IN6")
		(34 "In16.Cu" signal "GND7")
		(2 "B.Cu" signal "BOTTOM")
		(9 "F.Adhes" user "F.Adhesive")
		(11 "B.Adhes" user "B.Adhesive")
		(13 "F.Paste" user "Package Geometry/Pastemask Top")
		(15 "B.Paste" user "Package Geometry/Pastemask Bottom")
		(5 "F.SilkS" user "Ref Des/Silkscreen Top")
		(7 "B.SilkS" user "Ref Des/Silkscreen Bottom")
		(1 "F.Mask" user "Board Geometry/Soldermask Top")
		(3 "B.Mask" user "Board Geometry/Soldermask Bottom")
		(17 "Dwgs.User" user "User.Drawings")
		(19 "Cmts.User" user "User.Comments")
		(21 "Eco1.User" user "User.Eco1")
		(23 "Eco2.User" user "User.Eco2")
		(25 "Edge.Cuts" user "Board Geometry/Outline")
		(27 "Margin" user)
		(31 "F.CrtYd" user "Package Geometry/Place Bound Top")
		(29 "B.CrtYd" user "Package Geometry/Place Bound Bottom")
		(35 "F.Fab" user "Ref Des/Assembly Top")
		(33 "B.Fab" user "Ref Des/Assembly Bottom")
	)
	(footprint ""
		(layer "B.Cu")
		(at 311.387236 -197.836028 -90)
		(property "Reference" "R6082"
			(at 0 0 90)
			(layer "B.SilkS")
			(hide yes)
			(effects
				(font
					(size 1.27 1.27)
				)
				(justify mirror)
			)
		)
		(property "Value" ""
			(at 0 0 90)
			(layer "B.Fab")
			(effects
				(font
					(size 1.27 1.27)
				)
				(justify mirror)
			)
		)
		(duplicate_pad_numbers_are_jumpers no)
		(fp_line
			(start -0.7874 0.4064)
			(end 0.7874 0.4064)
			(stroke
				(width 0.1524)
				(type default)
			)
			(layer "B.SilkS")
		)
		(fp_line
			(start 0.7874 0.4064)
			(end 0.7874 -0.4064)
			(stroke
				(width 0.1524)
				(type default)
			)
			(layer "B.SilkS")
		)
		(fp_line
			(start -0.7874 -0.4064)
			(end -0.7874 0.4064)
			(stroke
				(width 0.1524)
				(type default)
			)
			(layer "B.SilkS")
		)
		(fp_line
			(start 0.7874 -0.4064)
			(end -0.7874 -0.4064)
			(stroke
				(width 0.1524)
				(type default)
			)
			(layer "B.SilkS")
		)
		(fp_line
			(start -0.67945 0.3048)
			(end -0.120396 0.3048)
			(stroke
				(width 0.1)
				(type default)
			)
			(layer "B.Fab")
		)
		(fp_line
			(start -0.120396 0.3048)
			(end -0.120396 0.2794)
			(stroke
				(width 0.1)
				(type default)
			)
			(layer "B.Fab")
		)
		(fp_line
			(start 0.12065 0.3048)
			(end 0.67945 0.3048)
			(stroke
				(width 0.1)
				(type default)
			)
			(layer "B.Fab")
		)
		(fp_line
			(start 0.67945 0.3048)
			(end 0.67945 -0.305054)
			(stroke
				(width 0.1)
				(type default)
			)
			(layer "B.Fab")
		)
		(fp_line
			(start -0.120396 0.2794)
			(end 0.12065 0.2794)
			(stroke
				(width 0.1)
				(type default)
			)
			(layer "B.Fab")
		)
		(fp_line
			(start 0.12065 0.2794)
			(end 0.12065 0.3048)
			(stroke
				(width 0.1)
				(type default)
			)
			(layer "B.Fab")
		)
		(fp_line
			(start -0.12065 -0.2794)
			(end -0.12065 -0.3048)
			(stroke
				(width 0.1)
				(type default)
			)
			(layer "B.Fab")
		)
		(fp_line
			(start 0.12065 -0.2794)
			(end -0.12065 -0.2794)
			(stroke
				(width 0.1)
				(type default)
			)
			(layer "B.Fab")
		)
		(fp_line
			(start -0.67945 -0.3048)
			(end -0.67945 0.3048)
			(stroke
				(width 0.1)
				(type default)
			)
			(layer "B.Fab")
		)
		(fp_line
			(start -0.12065 -0.3048)
			(end -0.67945 -0.3048)
			(stroke
				(width 0.1)
				(type default)
			)
			(layer "B.Fab")
		)
		(fp_line
			(start 0.12065 -0.305054)
			(end 0.12065 -0.2794)
			(stroke
				(width 0.1)
				(type default)
			)
			(layer "B.Fab")
		)
		(fp_line
			(start 0.67945 -0.305054)
			(end 0.12065 -0.305054)
			(stroke
				(width 0.1)
				(type default)
			)
			(layer "B.Fab")
		)
		(pad "1" smd circle
			(at 0.40005 0 90)
			(size 0 0)
			(layers "B.Cu" "B.Mask" "B.Paste")
			(net "PVDD11_S3_P0")
		)
		(pad "2" smd circle
			(at -0.40005 0 90)
			(size 0 0)
			(layers "B.Cu" "B.Mask" "B.Paste")
			(net "SMB_CPU0_2_SDA")
		)
	)
	(footprint ""
		(layer "B.Cu")
		(at 255.757426 -325.056754 180)
		(property "Reference" "C1085"
			(at 0 0 0)
			(layer "B.SilkS")
			(hide yes)
			(effects
				(font
					(size 1.27 1.27)
				)
				(justify mirror)
			)
		)
		(property "Value" ""
			(at 0 0 0)
			(layer "B.Fab")
			(effects
				(font
					(size 1.27 1.27)
				)
				(justify mirror)
			)
		)
		(duplicate_pad_numbers_are_jumpers no)
		(fp_line
			(start 0.7874 0.4064)
			(end 0.7874 -0.4064)
			(stroke
				(width 0.1524)
				(type default)
			)
			(layer "B.SilkS")
		)
		(fp_line
			(start 0.7874 -0.4064)
			(end -0.7874 -0.4064)
			(stroke
				(width 0.1524)
				(type default)
			)
			(layer "B.SilkS")
		)
		(fp_line
			(start -0.7874 0.4064)
			(end 0.7874 0.4064)
			(stroke
				(width 0.1524)
				(type default)
			)
			(layer "B.SilkS")
		)
		(fp_line
			(start -0.7874 -0.4064)
			(end -0.7874 0.4064)
			(stroke
				(width 0.1524)
				(type default)
			)
			(layer "B.SilkS")
		)
		(fp_line
			(start 0.67945 0.3048)
			(end 0.67945 -0.305054)
			(stroke
				(width 0.1)
				(type default)
			)
			(layer "B.Fab")
		)
		(fp_line
			(start 0.67945 -0.305054)
			(end 0.12065 -0.305054)
			(stroke
				(width 0.1)
				(type default)
			)
			(layer "B.Fab")
		)
		(fp_line
			(start 0.12065 0.3048)
			(end 0.67945 0.3048)
			(stroke
				(width 0.1)
				(type default)
			)
			(layer "B.Fab")
		)
		(fp_line
			(start 0.12065 0.2794)
			(end 0.12065 0.3048)
			(stroke
				(width 0.1)
				(type default)
			)
			(layer "B.Fab")
		)
		(fp_line
			(start 0.12065 -0.2794)
			(end -0.12065 -0.2794)
			(stroke
				(width 0.1)
				(type default)
			)
			(layer "B.Fab")
		)
		(fp_line
			(start 0.12065 -0.305054)
			(end 0.12065 -0.2794)
			(stroke
				(width 0.1)
				(type default)
			)
			(layer "B.Fab")
		)
		(fp_line
			(start -0.120396 0.3048)
			(end -0.120396 0.2794)
			(stroke
				(width 0.1)
				(type default)
			)
			(layer "B.Fab")
		)
		(fp_line
			(start -0.120396 0.2794)
			(end 0.12065 0.2794)
			(stroke
				(width 0.1)
				(type default)
			)
			(layer "B.Fab")
		)
		(fp_line
			(start -0.12065 -0.2794)
			(end -0.12065 -0.3048)
			(stroke
				(width 0.1)
				(type default)
			)
			(layer "B.Fab")
		)
		(fp_line
			(start -0.12065 -0.3048)
			(end -0.67945 -0.3048)
			(stroke
				(width 0.1)
				(type default)
			)
			(layer "B.Fab")
		)
		(fp_line
			(start -0.67945 0.3048)
			(end -0.120396 0.3048)
			(stroke
				(width 0.1)
				(type default)
			)
			(layer "B.Fab")
		)
		(fp_line
			(start -0.67945 -0.3048)
			(end -0.67945 0.3048)
			(stroke
				(width 0.1)
				(type default)
			)
			(layer "B.Fab")
		)
		(pad "1" smd circle
			(at 0.40005 0)
			(size 0 0)
			(layers "B.Cu" "B.Mask" "B.Paste")
			(net "P5V_AUX_ADC_MAM")
		)
		(pad "2" smd circle
			(at -0.40005 0)
			(size 0 0)
			(layers "B.Cu" "B.Mask" "B.Paste")
			(net "GND")
		)
	)
)
